(kicad_pcb
	(version 20260206)
	(generator "pcbnew")
	(generator_version "10.0")
	(general
		(thickness 1.6)
		(legacy_teardrops no)
	)
	(paper "A4")
	(title_block
		(title "9052_F0T_PDB_Converter_Brick_F_V03_1208_1600_OCP.brd")
		(comment 1 "Grand Teton / footprints 345-350 of 578")
	)
	(layers
		(0 "F.Cu" signal "TOP")
		(4 "In1.Cu" signal "GND")
		(6 "In2.Cu" signal "IN1")
		(8 "In3.Cu" signal "GND1")
		(10 "In4.Cu" signal "VCC")
		(12 "In5.Cu" signal "VCC1")
		(14 "In6.Cu" signal "GND2")
		(16 "In7.Cu" signal "IN2")
		(18 "In8.Cu" signal "GND3")
		(2 "B.Cu" signal "BOTTOM")
		(9 "F.Adhes" user "F.Adhesive")
		(11 "B.Adhes" user "B.Adhesive")
		(13 "F.Paste" user "Package Geometry/Pastemask Top")
		(15 "B.Paste" user "Package Geometry/Pastemask Bottom")
		(5 "F.SilkS" user "Ref Des/Silkscreen Top")
		(7 "B.SilkS" user "Ref Des/Silkscreen Bottom")
		(1 "F.Mask" user "Board Geometry/Soldermask Top")
		(3 "B.Mask" user "Board Geometry/Soldermask Bottom")
		(17 "Dwgs.User" user "User.Drawings")
		(19 "Cmts.User" user "User.Comments")
		(21 "Eco1.User" user "User.Eco1")
		(23 "Eco2.User" user "User.Eco2")
		(25 "Edge.Cuts" user "Board Geometry/Outline")
		(27 "Margin" user)
		(31 "F.CrtYd" user "Package Geometry/Place Bound Top")
		(29 "B.CrtYd" user "Package Geometry/Place Bound Bottom")
		(35 "F.Fab" user "Ref Des/Assembly Top")
		(33 "B.Fab" user "Ref Des/Assembly Bottom")
	)
	(footprint ""
		(layer "B.Cu")
		(at 223.52 -78.359 -90)
		(property "Reference" "R40"
			(at 0 0 90)
			(layer "B.SilkS")
			(hide yes)
			(effects
				(font
					(size 1.27 1.27)
				)
				(justify mirror)
			)
		)
		(property "Value" ""
			(at 0 0 90)
			(layer "B.Fab")
			(effects
				(font
					(size 1.27 1.27)
				)
				(justify mirror)
			)
		)
		(duplicate_pad_numbers_are_jumpers no)
		(fp_line
			(start -0.7874 0.4064)
			(end 0.7874 0.4064)
			(stroke
				(width 0.1524)
				(type default)
			)
			(layer "B.SilkS")
		)
		(fp_line
			(start 0.7874 0.4064)
			(end 0.7874 -0.4064)
			(stroke
				(width 0.1524)
				(type default)
			)
			(layer "B.SilkS")
		)
		(fp_line
			(start -0.7874 -0.4064)
			(end -0.7874 0.4064)
			(stroke
				(width 0.1524)
				(type default)
			)
			(layer "B.SilkS")
		)
		(fp_line
			(start 0.7874 -0.4064)
			(end -0.7874 -0.4064)
			(stroke
				(width 0.1524)
				(type default)
			)
			(layer "B.SilkS")
		)
		(fp_line
			(start -0.67945 0.3048)
			(end -0.120396 0.3048)
			(stroke
				(width 0.1)
				(type default)
			)
			(layer "B.Fab")
		)
		(fp_line
			(start -0.120396 0.3048)
			(end -0.120396 0.2794)
			(stroke
				(width 0.1)
				(type default)
			)
			(layer "B.Fab")
		)
		(fp_line
			(start 0.12065 0.3048)
			(end 0.67945 0.3048)
			(stroke
				(width 0.1)
				(type default)
			)
			(layer "B.Fab")
		)
		(fp_line
			(start 0.67945 0.3048)
			(end 0.67945 -0.305054)
			(stroke
				(width 0.1)
				(type default)
			)
			(layer "B.Fab")
		)
		(fp_line
			(start -0.120396 0.2794)
			(end 0.12065 0.2794)
			(stroke
				(width 0.1)
				(type default)
			)
			(layer "B.Fab")
		)
		(fp_line
			(start 0.12065 0.2794)
			(end 0.12065 0.3048)
			(stroke
				(width 0.1)
				(type default)
			)
			(layer "B.Fab")
		)
		(fp_line
			(start -0.12065 -0.2794)
			(end -0.12065 -0.3048)
			(stroke
				(width 0.1)
				(type default)
			)
			(layer "B.Fab")
		)
		(fp_line
			(start 0.12065 -0.2794)
			(end -0.12065 -0.2794)
			(stroke
				(width 0.1)
				(type default)
			)
			(layer "B.Fab")
		)
		(fp_line
			(start -0.67945 -0.3048)
			(end -0.67945 0.3048)
			(stroke
				(width 0.1)
				(type default)
			)
			(layer "B.Fab")
		)
		(fp_line
			(start -0.12065 -0.3048)
			(end -0.67945 -0.3048)
			(stroke
				(width 0.1)
				(type default)
			)
			(layer "B.Fab")
		)
		(fp_line
			(start 0.12065 -0.305054)
			(end 0.12065 -0.2794)
			(stroke
				(width 0.1)
				(type default)
			)
			(layer "B.Fab")
		)
		(fp_line
			(start 0.67945 -0.305054)
			(end 0.12065 -0.305054)
			(stroke
				(width 0.1)
				(type default)
			)
			(layer "B.Fab")
		)
		(pad "1" smd circle
			(at 0.40005 0 90)
			(size 0 0)
			(layers "B.Cu" "B.Mask" "B.Paste")
			(net "P3V3_AUX")
		)
		(pad "2" smd circle
			(at -0.40005 0 90)
			(size 0 0)
			(layers "B.Cu" "B.Mask" "B.Paste")
			(net "FRU_ADDR0")
		)
	)
	(footprint ""
		(layer "B.Cu")
		(at 132.850128 -76.708 -90)
		(property "Reference" "PR52"
			(at 0 0 90)
			(layer "B.SilkS")
			(hide yes)
			(effects
				(font
					(size 1.27 1.27)
				)
				(justify mirror)
			)
		)
		(property "Value" ""
			(at 0 0 90)
			(layer "B.Fab")
			(effects
				(font
					(size 1.27 1.27)
				)
				(justify mirror)
			)
		)
		(duplicate_pad_numbers_are_jumpers no)
		(fp_line
			(start -0.7874 0.4064)
			(end 0.7874 0.4064)
			(stroke
				(width 0.1524)
				(type default)
			)
			(layer "B.SilkS")
		)
		(fp_line
			(start 0.7874 0.4064)
			(end 0.7874 -0.4064)
			(stroke
				(width 0.1524)
				(type default)
			)
			(layer "B.SilkS")
		)
		(fp_line
			(start -0.7874 -0.4064)
			(end -0.7874 0.4064)
			(stroke
				(width 0.1524)
				(type default)
			)
			(layer "B.SilkS")
		)
		(fp_line
			(start 0.7874 -0.4064)
			(end -0.7874 -0.4064)
			(stroke
				(width 0.1524)
				(type default)
			)
			(layer "B.SilkS")
		)
		(fp_line
			(start -0.67945 0.3048)
			(end -0.120396 0.3048)
			(stroke
				(width 0.1)
				(type default)
			)
			(layer "B.Fab")
		)
		(fp_line
			(start -0.120396 0.3048)
			(end -0.120396 0.2794)
			(stroke
				(width 0.1)
				(type default)
			)
			(layer "B.Fab")
		)
		(fp_line
			(start 0.12065 0.3048)
			(end 0.67945 0.3048)
			(stroke
				(width 0.1)
				(type default)
			)
			(layer "B.Fab")
		)
		(fp_line
			(start 0.67945 0.3048)
			(end 0.67945 -0.305054)
			(stroke
				(width 0.1)
				(type default)
			)
			(layer "B.Fab")
		)
		(fp_line
			(start -0.120396 0.2794)
			(end 0.12065 0.2794)
			(stroke
				(width 0.1)
				(type default)
			)
			(layer "B.Fab")
		)
		(fp_line
			(start 0.12065 0.2794)
			(end 0.12065 0.3048)
			(stroke
				(width 0.1)
				(type default)
			)
			(layer "B.Fab")
		)
		(fp_line
			(start -0.12065 -0.2794)
			(end -0.12065 -0.3048)
			(stroke
				(width 0.1)
				(type default)
			)
			(layer "B.Fab")
		)
		(fp_line
			(start 0.12065 -0.2794)
			(end -0.12065 -0.2794)
			(stroke
				(width 0.1)
				(type default)
			)
			(layer "B.Fab")
		)
		(fp_line
			(start -0.67945 -0.3048)
			(end -0.67945 0.3048)
			(stroke
				(width 0.1)
				(type default)
			)
			(layer "B.Fab")
		)
		(fp_line
			(start -0.12065 -0.3048)
			(end -0.67945 -0.3048)
			(stroke
				(width 0.1)
				(type default)
			)
			(layer "B.Fab")
		)
		(fp_line
			(start 0.12065 -0.305054)
			(end 0.12065 -0.2794)
			(stroke
				(width 0.1)
				(type default)
			)
			(layer "B.Fab")
		)
		(fp_line
			(start 0.67945 -0.305054)
			(end 0.12065 -0.305054)
			(stroke
				(width 0.1)
				(type default)
			)
			(layer "B.Fab")
		)
		(pad "1" smd circle
			(at 0.40005 0 90)
			(size 0 0)
			(layers "B.Cu" "B.Mask" "B.Paste")
			(net "P12V_MB0_SENSE-")
		)
		(pad "2" smd circle
			(at -0.40005 0 90)
			(size 0 0)
			(layers "B.Cu" "B.Mask" "B.Paste")
			(net "GND")
		)
	)
	(footprint ""
		(layer "B.Cu")
		(at 205.74 -86.614 180)
		(property "Reference" "R126"
			(at 0 0 0)
			(layer "B.SilkS")
			(hide yes)
			(effects
				(font
					(size 1.27 1.27)
				)
				(justify mirror)
			)
		)
		(property "Value" ""
			(at 0 0 0)
			(layer "B.Fab")
			(effects
				(font
					(size 1.27 1.27)
				)
				(justify mirror)
			)
		)
		(duplicate_pad_numbers_are_jumpers no)
		(fp_line
			(start 0.7874 0.4064)
			(end 0.7874 -0.4064)
			(stroke
				(width 0.1524)
				(type default)
			)
			(layer "B.SilkS")
		)
		(fp_line
			(start 0.7874 -0.4064)
			(end -0.7874 -0.4064)
			(stroke
				(width 0.1524)
				(type default)
			)
			(layer "B.SilkS")
		)
		(fp_line
			(start -0.7874 0.4064)
			(end 0.7874 0.4064)
			(stroke
				(width 0.1524)
				(type default)
			)
			(layer "B.SilkS")
		)
		(fp_line
			(start -0.7874 -0.4064)
			(end -0.7874 0.4064)
			(stroke
				(width 0.1524)
				(type default)
			)
			(layer "B.SilkS")
		)
		(fp_line
			(start 0.67945 0.3048)
			(end 0.67945 -0.305054)
			(stroke
				(width 0.1)
				(type default)
			)
			(layer "B.Fab")
		)
		(fp_line
			(start 0.67945 -0.305054)
			(end 0.12065 -0.305054)
			(stroke
				(width 0.1)
				(type default)
			)
			(layer "B.Fab")
		)
		(fp_line
			(start 0.12065 0.3048)
			(end 0.67945 0.3048)
			(stroke
				(width 0.1)
				(type default)
			)
			(layer "B.Fab")
		)
		(fp_line
			(start 0.12065 0.2794)
			(end 0.12065 0.3048)
			(stroke
				(width 0.1)
				(type default)
			)
			(layer "B.Fab")
		)
		(fp_line
			(start 0.12065 -0.2794)
			(end -0.12065 -0.2794)
			(stroke
				(width 0.1)
				(type default)
			)
			(layer "B.Fab")
		)
		(fp_line
			(start 0.12065 -0.305054)
			(end 0.12065 -0.2794)
			(stroke
				(width 0.1)
				(type default)
			)
			(layer "B.Fab")
		)
		(fp_line
			(start -0.120396 0.3048)
			(end -0.120396 0.2794)
			(stroke
				(width 0.1)
				(type default)
			)
			(layer "B.Fab")
		)
		(fp_line
			(start -0.120396 0.2794)
			(end 0.12065 0.2794)
			(stroke
				(width 0.1)
				(type default)
			)
			(layer "B.Fab")
		)
		(fp_line
			(start -0.12065 -0.2794)
			(end -0.12065 -0.3048)
			(stroke
				(width 0.1)
				(type default)
			)
			(layer "B.Fab")
		)
		(fp_line
			(start -0.12065 -0.3048)
			(end -0.67945 -0.3048)
			(stroke
				(width 0.1)
				(type default)
			)
			(layer "B.Fab")
		)
		(fp_line
			(start -0.67945 0.3048)
			(end -0.120396 0.3048)
			(stroke
				(width 0.1)
				(type default)
			)
			(layer "B.Fab")
		)
		(fp_line
			(start -0.67945 -0.3048)
			(end -0.67945 0.3048)
			(stroke
				(width 0.1)
				(type default)
			)
			(layer "B.Fab")
		)
		(pad "1" smd circle
			(at 0.40005 0)
			(size 0 0)
			(layers "B.Cu" "B.Mask" "B.Paste")
			(net "SMB_VPDB_MISC_SCL")
		)
		(pad "2" smd circle
			(at -0.40005 0)
			(size 0 0)
			(layers "B.Cu" "B.Mask" "B.Paste")
			(net "P3V3_AUX")
		)
	)
	(footprint ""
		(layer "B.Cu")
		(at 96.52 -76.327 180)
		(property "Reference" "R173"
			(at 0 0 0)
			(layer "B.SilkS")
			(hide yes)
			(effects
				(font
					(size 1.27 1.27)
				)
				(justify mirror)
			)
		)
		(property "Value" ""
			(at 0 0 0)
			(layer "B.Fab")
			(effects
				(font
					(size 1.27 1.27)
				)
				(justify mirror)
			)
		)
		(duplicate_pad_numbers_are_jumpers no)
		(fp_line
			(start 0.7874 0.4064)
			(end 0.7874 -0.4064)
			(stroke
				(width 0.1524)
				(type default)
			)
			(layer "B.SilkS")
		)
		(fp_line
			(start 0.7874 -0.4064)
			(end -0.7874 -0.4064)
			(stroke
				(width 0.1524)
				(type default)
			)
			(layer "B.SilkS")
		)
		(fp_line
			(start -0.7874 0.4064)
			(end 0.7874 0.4064)
			(stroke
				(width 0.1524)
				(type default)
			)
			(layer "B.SilkS")
		)
		(fp_line
			(start -0.7874 -0.4064)
			(end -0.7874 0.4064)
			(stroke
				(width 0.1524)
				(type default)
			)
			(layer "B.SilkS")
		)
		(fp_line
			(start 0.67945 0.3048)
			(end 0.67945 -0.305054)
			(stroke
				(width 0.1)
				(type default)
			)
			(layer "B.Fab")
		)
		(fp_line
			(start 0.67945 -0.305054)
			(end 0.12065 -0.305054)
			(stroke
				(width 0.1)
				(type default)
			)
			(layer "B.Fab")
		)
		(fp_line
			(start 0.12065 0.3048)
			(end 0.67945 0.3048)
			(stroke
				(width 0.1)
				(type default)
			)
			(layer "B.Fab")
		)
		(fp_line
			(start 0.12065 0.2794)
			(end 0.12065 0.3048)
			(stroke
				(width 0.1)
				(type default)
			)
			(layer "B.Fab")
		)
		(fp_line
			(start 0.12065 -0.2794)
			(end -0.12065 -0.2794)
			(stroke
				(width 0.1)
				(type default)
			)
			(layer "B.Fab")
		)
		(fp_line
			(start 0.12065 -0.305054)
			(end 0.12065 -0.2794)
			(stroke
				(width 0.1)
				(type default)
			)
			(layer "B.Fab")
		)
		(fp_line
			(start -0.120396 0.3048)
			(end -0.120396 0.2794)
			(stroke
				(width 0.1)
				(type default)
			)
			(layer "B.Fab")
		)
		(fp_line
			(start -0.120396 0.2794)
			(end 0.12065 0.2794)
			(stroke
				(width 0.1)
				(type default)
			)
			(layer "B.Fab")
		)
		(fp_line
			(start -0.12065 -0.2794)
			(end -0.12065 -0.3048)
			(stroke
				(width 0.1)
				(type default)
			)
			(layer "B.Fab")
		)
		(fp_line
			(start -0.12065 -0.3048)
			(end -0.67945 -0.3048)
			(stroke
				(width 0.1)
				(type default)
			)
			(layer "B.Fab")
		)
		(fp_line
			(start -0.67945 0.3048)
			(end -0.120396 0.3048)
			(stroke
				(width 0.1)
				(type default)
			)
			(layer "B.Fab")
		)
		(fp_line
			(start -0.67945 -0.3048)
			(end -0.67945 0.3048)
			(stroke
				(width 0.1)
				(type default)
			)
			(layer "B.Fab")
		)
		(pad "1" smd circle
			(at 0.40005 0)
			(size 0 0)
			(layers "B.Cu" "B.Mask" "B.Paste")
			(net "SMB_P52V_VPDB_SCL")
		)
		(pad "2" smd circle
			(at -0.40005 0)
			(size 0 0)
			(layers "B.Cu" "B.Mask" "B.Paste")
			(net "SMB_BRICK1_SCL")
		)
	)
	(footprint ""
		(layer "B.Cu")
		(at 230.632 -82.296 90)
		(property "Reference" "R140"
			(at 0 0 90)
			(layer "B.SilkS")
			(hide yes)
			(effects
				(font
					(size 1.27 1.27)
				)
				(justify mirror)
			)
		)
		(property "Value" ""
			(at 0 0 90)
			(layer "B.Fab")
			(effects
				(font
					(size 1.27 1.27)
				)
				(justify mirror)
			)
		)
		(duplicate_pad_numbers_are_jumpers no)
		(fp_line
			(start 0.7874 -0.4064)
			(end -0.7874 -0.4064)
			(stroke
				(width 0.1524)
				(type default)
			)
			(layer "B.SilkS")
		)
		(fp_line
			(start -0.7874 -0.4064)
			(end -0.7874 0.4064)
			(stroke
				(width 0.1524)
				(type default)
			)
			(layer "B.SilkS")
		)
		(fp_line
			(start 0.7874 0.4064)
			(end 0.7874 -0.4064)
			(stroke
				(width 0.1524)
				(type default)
			)
			(layer "B.SilkS")
		)
		(fp_line
			(start -0.7874 0.4064)
			(end 0.7874 0.4064)
			(stroke
				(width 0.1524)
				(type default)
			)
			(layer "B.SilkS")
		)
		(fp_line
			(start 0.67945 -0.305054)
			(end 0.12065 -0.305054)
			(stroke
				(width 0.1)
				(type default)
			)
			(layer "B.Fab")
		)
		(fp_line
			(start 0.12065 -0.305054)
			(end 0.12065 -0.2794)
			(stroke
				(width 0.1)
				(type default)
			)
			(layer "B.Fab")
		)
		(fp_line
			(start -0.12065 -0.3048)
			(end -0.67945 -0.3048)
			(stroke
				(width 0.1)
				(type default)
			)
			(layer "B.Fab")
		)
		(fp_line
			(start -0.67945 -0.3048)
			(end -0.67945 0.3048)
			(stroke
				(width 0.1)
				(type default)
			)
			(layer "B.Fab")
		)
		(fp_line
			(start 0.12065 -0.2794)
			(end -0.12065 -0.2794)
			(stroke
				(width 0.1)
				(type default)
			)
			(layer "B.Fab")
		)
		(fp_line
			(start -0.12065 -0.2794)
			(end -0.12065 -0.3048)
			(stroke
				(width 0.1)
				(type default)
			)
			(layer "B.Fab")
		)
		(fp_line
			(start 0.12065 0.2794)
			(end 0.12065 0.3048)
			(stroke
				(width 0.1)
				(type default)
			)
			(layer "B.Fab")
		)
		(fp_line
			(start -0.120396 0.2794)
			(end 0.12065 0.2794)
			(stroke
				(width 0.1)
				(type default)
			)
			(layer "B.Fab")
		)
		(fp_line
			(start 0.67945 0.3048)
			(end 0.67945 -0.305054)
			(stroke
				(width 0.1)
				(type default)
			)
			(layer "B.Fab")
		)
		(fp_line
			(start 0.12065 0.3048)
			(end 0.67945 0.3048)
			(stroke
				(width 0.1)
				(type default)
			)
			(layer "B.Fab")
		)
		(fp_line
			(start -0.120396 0.3048)
			(end -0.120396 0.2794)
			(stroke
				(width 0.1)
				(type default)
			)
			(layer "B.Fab")
		)
		(fp_line
			(start -0.67945 0.3048)
			(end -0.120396 0.3048)
			(stroke
				(width 0.1)
				(type default)
			)
			(layer "B.Fab")
		)
		(pad "1" smd circle
			(at 0.40005 0 270)
			(size 0 0)
			(layers "B.Cu" "B.Mask" "B.Paste")
			(net "GND")
		)
		(pad "2" smd circle
			(at -0.40005 0 270)
			(size 0 0)
			(layers "B.Cu" "B.Mask" "B.Paste")
			(net "PWRGD_P3V3_AUX_MB_BUF_R")
		)
	)
	(footprint ""
		(layer "B.Cu")
		(at 205.74 -91.948 180)
		(property "Reference" "R97"
			(at 0 0 0)
			(layer "B.SilkS")
			(hide yes)
			(effects
				(font
					(size 1.27 1.27)
				)
				(justify mirror)
			)
		)
		(property "Value" ""
			(at 0 0 0)
			(layer "B.Fab")
			(effects
				(font
					(size 1.27 1.27)
				)
				(justify mirror)
			)
		)
		(duplicate_pad_numbers_are_jumpers no)
		(fp_line
			(start 0.7874 0.4064)
			(end 0.7874 -0.4064)
			(stroke
				(width 0.1524)
				(type default)
			)
			(layer "B.SilkS")
		)
		(fp_line
			(start 0.7874 -0.4064)
			(end -0.7874 -0.4064)
			(stroke
				(width 0.1524)
				(type default)
			)
			(layer "B.SilkS")
		)
		(fp_line
			(start -0.7874 0.4064)
			(end 0.7874 0.4064)
			(stroke
				(width 0.1524)
				(type default)
			)
			(layer "B.SilkS")
		)
		(fp_line
			(start -0.7874 -0.4064)
			(end -0.7874 0.4064)
			(stroke
				(width 0.1524)
				(type default)
			)
			(layer "B.SilkS")
		)
		(fp_line
			(start 0.67945 0.3048)
			(end 0.67945 -0.305054)
			(stroke
				(width 0.1)
				(type default)
			)
			(layer "B.Fab")
		)
		(fp_line
			(start 0.67945 -0.305054)
			(end 0.12065 -0.305054)
			(stroke
				(width 0.1)
				(type default)
			)
			(layer "B.Fab")
		)
		(fp_line
			(start 0.12065 0.3048)
			(end 0.67945 0.3048)
			(stroke
				(width 0.1)
				(type default)
			)
			(layer "B.Fab")
		)
		(fp_line
			(start 0.12065 0.2794)
			(end 0.12065 0.3048)
			(stroke
				(width 0.1)
				(type default)
			)
			(layer "B.Fab")
		)
		(fp_line
			(start 0.12065 -0.2794)
			(end -0.12065 -0.2794)
			(stroke
				(width 0.1)
				(type default)
			)
			(layer "B.Fab")
		)
		(fp_line
			(start 0.12065 -0.305054)
			(end 0.12065 -0.2794)
			(stroke
				(width 0.1)
				(type default)
			)
			(layer "B.Fab")
		)
		(fp_line
			(start -0.120396 0.3048)
			(end -0.120396 0.2794)
			(stroke
				(width 0.1)
				(type default)
			)
			(layer "B.Fab")
		)
		(fp_line
			(start -0.120396 0.2794)
			(end 0.12065 0.2794)
			(stroke
				(width 0.1)
				(type default)
			)
			(layer "B.Fab")
		)
		(fp_line
			(start -0.12065 -0.2794)
			(end -0.12065 -0.3048)
			(stroke
				(width 0.1)
				(type default)
			)
			(layer "B.Fab")
		)
		(fp_line
			(start -0.12065 -0.3048)
			(end -0.67945 -0.3048)
			(stroke
				(width 0.1)
				(type default)
			)
			(layer "B.Fab")
		)
		(fp_line
			(start -0.67945 0.3048)
			(end -0.120396 0.3048)
			(stroke
				(width 0.1)
				(type default)
			)
			(layer "B.Fab")
		)
		(fp_line
			(start -0.67945 -0.3048)
			(end -0.67945 0.3048)
			(stroke
				(width 0.1)
				(type default)
			)
			(layer "B.Fab")
		)
		(pad "1" smd circle
			(at 0.40005 0)
			(size 0 0)
			(layers "B.Cu" "B.Mask" "B.Paste")
			(net "PCA9543_MISC_A0")
		)
		(pad "2" smd circle
			(at -0.40005 0)
			(size 0 0)
			(layers "B.Cu" "B.Mask" "B.Paste")
			(net "GND")
		)
	)
)
